(kicad_pcb
	(version 20241229)
	(generator "pcbnew")
	(generator_version "9.0")
	(general
		(thickness 1.294)
		(legacy_teardrops no)
	)
	(paper "A3")
	(title_block
		(title "Kintex 410T devboard")
		(date "2024-04-03")
		(rev "1.1.2")
		(comment 9 "footprints 27-32 of 975")
	)
	(layers
		(0 "F.Cu" mixed)
		(4 "In1.Cu" power)
		(6 "In2.Cu" power)
		(8 "In3.Cu" mixed)
		(10 "In4.Cu" power)
		(12 "In5.Cu" mixed)
		(14 "In6.Cu" power)
		(16 "In7.Cu" mixed)
		(18 "In8.Cu" power)
		(2 "B.Cu" mixed)
		(9 "F.Adhes" user "F.Adhesive")
		(11 "B.Adhes" user "B.Adhesive")
		(13 "F.Paste" user)
		(15 "B.Paste" user)
		(5 "F.SilkS" user "F.Silkscreen")
		(7 "B.SilkS" user "B.Silkscreen")
		(1 "F.Mask" user)
		(3 "B.Mask" user)
		(17 "Dwgs.User" user "User.Drawings")
		(19 "Cmts.User" user "User.Comments")
		(21 "Eco1.User" user "User.Eco1")
		(23 "Eco2.User" user "User.Eco2")
		(25 "Edge.Cuts" user)
		(27 "Margin" user)
		(31 "F.CrtYd" user "F.Courtyard")
		(29 "B.CrtYd" user "B.Courtyard")
		(35 "F.Fab" user)
		(33 "B.Fab" user)
	)
	(footprint "antmicro-footprints:C_0603_1608Metric"
		(layer "F.Cu")
		(at 174.9 164 180)
		(descr "Capacitor SMD 0603")
		(tags "capacitor 0603")
		(property "Reference" "C324"
			(at 1 -0.4 0)
			(layer "F.SilkS")
			(effects
				(font
					(size 0.7 0.7)
					(thickness 0.15)
				)
				(justify right bottom)
			)
		)
		(property "Value" "C_22u_0603"
			(at 0 1.6 0)
			(layer "F.Fab")
			(effects
				(font
					(size 0.7 0.7)
					(thickness 0.15)
				)
				(justify right bottom)
			)
		)
		(property "Description" "SMD Multilayer Ceramic Capacitor, 22 µF, 6.3 V, 0603 [1608 Metric], ± 20%, X5R, GRM Series"
			(at 0 0 180)
			(layer "F.Fab")
			(hide yes)
			(effects
				(font
					(size 1.27 1.27)
					(thickness 0.15)
				)
			)
		)
		(property "Author" "Antmicro"
			(at 349.8 328 0)
			(layer "F.Fab")
			(hide yes)
			(effects
				(font
					(size 1 1)
					(thickness 0.15)
				)
			)
		)
		(property "Dielectric" ""
			(at 349.8 328 0)
			(layer "F.Fab")
			(hide yes)
			(effects
				(font
					(size 1 1)
					(thickness 0.15)
				)
			)
		)
		(property "License" "Apache-2.0"
			(at 349.8 328 0)
			(layer "F.Fab")
			(hide yes)
			(effects
				(font
					(size 1 1)
					(thickness 0.15)
				)
			)
		)
		(property "MPN" "GRM188R60J226MEA0D"
			(at 349.8 328 0)
			(layer "F.Fab")
			(hide yes)
			(effects
				(font
					(size 1 1)
					(thickness 0.15)
				)
			)
		)
		(property "Manufacturer" "Murata"
			(at 349.8 328 0)
			(layer "F.Fab")
			(hide yes)
			(effects
				(font
					(size 1 1)
					(thickness 0.15)
				)
			)
		)
		(property "Val" "22u"
			(at 349.8 328 0)
			(layer "F.Fab")
			(hide yes)
			(effects
				(font
					(size 1 1)
					(thickness 0.15)
				)
			)
		)
		(property "Voltage" ""
			(at 349.8 328 0)
			(layer "F.Fab")
			(hide yes)
			(effects
				(font
					(size 1 1)
					(thickness 0.15)
				)
			)
		)
		(sheetname "DC-DC Converters")
		(sheetfile "dc-dc.kicad_sch")
		(attr smd)
		(fp_line
			(start -0.15 0.4)
			(end 0.15 0.4)
			(stroke
				(width 0.15)
				(type solid)
			)
			(layer "F.SilkS")
		)
		(fp_line
			(start -0.15 -0.4)
			(end 0.15 -0.4)
			(stroke
				(width 0.15)
				(type solid)
			)
			(layer "F.SilkS")
		)
		(fp_rect
			(start -1.25 -0.65)
			(end 1.25 0.65)
			(stroke
				(width 0.05)
				(type solid)
			)
			(fill no)
			(layer "F.CrtYd")
		)
		(fp_rect
			(start -0.8 -0.4)
			(end 0.8 0.4)
			(stroke
				(width 0.15)
				(type solid)
			)
			(fill no)
			(layer "F.Fab")
		)
		(pad "1" smd roundrect
			(at -0.7 0 180)
			(size 0.8 1)
			(layers "F.Cu" "F.Mask" "F.Paste")
			(roundrect_rratio 0.2)
			(net 1 "GND")
			(pintype "passive")
		)
		(pad "2" smd roundrect
			(at 0.7 0 180)
			(size 0.8 1)
			(layers "F.Cu" "F.Mask" "F.Paste")
			(roundrect_rratio 0.2)
			(net 735 "/DC-DC Converters/3V3_local")
			(pintype "passive")
		)
	)
	(footprint "antmicro-footprints:R_0402_1005Metric"
		(layer "F.Cu")
		(at 151.975 155.25 180)
		(descr "Resistor SMD 0402")
		(tags "resistor SMD 0402")
		(property "Reference" "R341"
			(at 1.575 0.5 180)
			(layer "F.SilkS")
			(effects
				(font
					(size 0.7 0.7)
					(thickness 0.15)
				)
				(justify left bottom)
			)
		)
		(property "Value" "R_100k_0402"
			(at 0 1.4 180)
			(layer "F.Fab")
			(effects
				(font
					(size 0.7 0.7)
					(thickness 0.15)
				)
				(justify left bottom)
			)
		)
		(property "Description" "SMD Chip Resistor, 100 kohm, ± 1%, 62.5 mW, 0402 [1005 Metric], Thick Film, General Purpose"
			(at 0 0 180)
			(layer "F.Fab")
			(hide yes)
			(effects
				(font
					(size 1.27 1.27)
					(thickness 0.15)
				)
			)
		)
		(property "Author" "Antmicro"
			(at 303.95 310.5 0)
			(layer "F.Fab")
			(hide yes)
			(effects
				(font
					(size 1 1)
					(thickness 0.15)
				)
			)
		)
		(property "License" "Apache-2.0"
			(at 303.95 310.5 0)
			(layer "F.Fab")
			(hide yes)
			(effects
				(font
					(size 1 1)
					(thickness 0.15)
				)
			)
		)
		(property "MPN" "CR0402-FX-1003GLF"
			(at 303.95 310.5 0)
			(layer "F.Fab")
			(hide yes)
			(effects
				(font
					(size 1 1)
					(thickness 0.15)
				)
			)
		)
		(property "Manufacturer" "Bourns"
			(at 303.95 310.5 0)
			(layer "F.Fab")
			(hide yes)
			(effects
				(font
					(size 1 1)
					(thickness 0.15)
				)
			)
		)
		(property "Tolerance" "1%"
			(at 303.95 310.5 0)
			(layer "F.Fab")
			(hide yes)
			(effects
				(font
					(size 1 1)
					(thickness 0.15)
				)
			)
		)
		(property "Val" "100k"
			(at 303.95 310.5 0)
			(layer "F.Fab")
			(hide yes)
			(effects
				(font
					(size 1 1)
					(thickness 0.15)
				)
			)
		)
		(sheetname "DC-DC Converters")
		(sheetfile "dc-dc.kicad_sch")
		(attr smd)
		(fp_rect
			(start -0.925 -0.47)
			(end 0.925 0.47)
			(stroke
				(width 0.05)
				(type default)
			)
			(fill no)
			(layer "F.CrtYd")
		)
		(fp_rect
			(start -0.5 -0.25)
			(end 0.5 0.25)
			(stroke
				(width 0.15)
				(type solid)
			)
			(fill no)
			(layer "F.Fab")
		)
		(pad "1" smd roundrect
			(at -0.48 0 180)
			(size 0.59 0.64)
			(layers "F.Cu" "F.Mask" "F.Paste")
			(roundrect_rratio 0.25)
			(net 1055 "/DC-DC Converters/VDDR_PGOOD")
			(pintype "passive")
		)
		(pad "2" smd roundrect
			(at 0.48 0 180)
			(size 0.59 0.64)
			(layers "F.Cu" "F.Mask" "F.Paste")
			(roundrect_rratio 0.25)
			(net 24 "+3V3")
			(pintype "passive")
		)
	)
	(footprint "antmicro-footprints:R_0402_1005Metric"
		(layer "F.Cu")
		(at 219.2 137.2 180)
		(descr "Resistor SMD 0402")
		(tags "resistor SMD 0402")
		(property "Reference" "R336"
			(at 3.65 -0.4 180)
			(layer "F.SilkS")
			(effects
				(font
					(size 0.7 0.7)
					(thickness 0.15)
				)
				(justify left bottom)
			)
		)
		(property "Value" "R_22R_0402"
			(at 0 1.4 180)
			(layer "F.Fab")
			(effects
				(font
					(size 0.7 0.7)
					(thickness 0.15)
				)
				(justify left bottom)
			)
		)
		(property "Description" "SMD Chip Resistor, 22 ohm, ± 1%, 62.5 mW, 0402 [1005 Metric], Thick Film, General Purpose"
			(at 0 0 180)
			(layer "F.Fab")
			(hide yes)
			(effects
				(font
					(size 1.27 1.27)
					(thickness 0.15)
				)
			)
		)
		(property "Author" "Antmicro"
			(at 438.4 274.4 0)
			(layer "F.Fab")
			(hide yes)
			(effects
				(font
					(size 1 1)
					(thickness 0.15)
				)
			)
		)
		(property "License" "Apache-2.0"
			(at 438.4 274.4 0)
			(layer "F.Fab")
			(hide yes)
			(effects
				(font
					(size 1 1)
					(thickness 0.15)
				)
			)
		)
		(property "MPN" "CR0402-FX-22R0GLF"
			(at 438.4 274.4 0)
			(layer "F.Fab")
			(hide yes)
			(effects
				(font
					(size 1 1)
					(thickness 0.15)
				)
			)
		)
		(property "Manufacturer" "Bourns"
			(at 438.4 274.4 0)
			(layer "F.Fab")
			(hide yes)
			(effects
				(font
					(size 1 1)
					(thickness 0.15)
				)
			)
		)
		(property "Tolerance" "1%"
			(at 438.4 274.4 0)
			(layer "F.Fab")
			(hide yes)
			(effects
				(font
					(size 1 1)
					(thickness 0.15)
				)
			)
		)
		(property "Val" "22R"
			(at 438.4 274.4 0)
			(layer "F.Fab")
			(hide yes)
			(effects
				(font
					(size 1 1)
					(thickness 0.15)
				)
			)
		)
		(sheetname "Clocks")
		(sheetfile "clocks.kicad_sch")
		(attr smd)
		(fp_rect
			(start -0.925 -0.47)
			(end 0.925 0.47)
			(stroke
				(width 0.05)
				(type default)
			)
			(fill no)
			(layer "F.CrtYd")
		)
		(fp_rect
			(start -0.5 -0.25)
			(end 0.5 0.25)
			(stroke
				(width 0.15)
				(type solid)
			)
			(fill no)
			(layer "F.Fab")
		)
		(pad "1" smd roundrect
			(at -0.48 0 180)
			(size 0.59 0.64)
			(layers "F.Cu" "F.Mask" "F.Paste")
			(roundrect_rratio 0.25)
			(net 972 "/Clocks/PLL_Y1")
			(pintype "passive")
		)
		(pad "2" smd roundrect
			(at 0.48 0 180)
			(size 0.59 0.64)
			(layers "F.Cu" "F.Mask" "F.Paste")
			(roundrect_rratio 0.25)
			(net 1402 "/PLL.CLK2")
			(pintype "passive")
		)
	)
	(footprint "antmicro-footprints:C_0402_1005Metric"
		(layer "F.Cu")
		(at 225.7 152.1 90)
		(descr "Capacitor SMD 0402")
		(tags "capacitor SMD 0402")
		(property "Reference" "C270"
			(at -1.65 1.3 90)
			(layer "F.SilkS")
			(effects
				(font
					(size 0.7 0.7)
					(thickness 0.15)
				)
				(justify left bottom)
			)
		)
		(property "Value" "C_100n_0402"
			(at 0 1.169 90)
			(layer "F.Fab")
			(effects
				(font
					(size 0.7 0.7)
					(thickness 0.15)
				)
				(justify left bottom)
			)
		)
		(property "Description" "SMD Multilayer Ceramic Capacitor, 0.1 µF, 50 V, 0402 [1005 Metric], ± 10%, X5R, GRM Series"
			(at 0 0 90)
			(layer "F.Fab")
			(hide yes)
			(effects
				(font
					(size 1.27 1.27)
					(thickness 0.15)
				)
			)
		)
		(property "Author" "Antmicro"
			(at 377.8 -73.6 0)
			(layer "F.Fab")
			(hide yes)
			(effects
				(font
					(size 1 1)
					(thickness 0.15)
				)
			)
		)
		(property "Dielectric" "X5R"
			(at 377.8 -73.6 0)
			(layer "F.Fab")
			(hide yes)
			(effects
				(font
					(size 1 1)
					(thickness 0.15)
				)
			)
		)
		(property "License" "Apache-2.0"
			(at 377.8 -73.6 0)
			(layer "F.Fab")
			(hide yes)
			(effects
				(font
					(size 1 1)
					(thickness 0.15)
				)
			)
		)
		(property "MPN" "GRM155R61H104KE14D"
			(at 377.8 -73.6 0)
			(layer "F.Fab")
			(hide yes)
			(effects
				(font
					(size 1 1)
					(thickness 0.15)
				)
			)
		)
		(property "Manufacturer" "Murata"
			(at 377.8 -73.6 0)
			(layer "F.Fab")
			(hide yes)
			(effects
				(font
					(size 1 1)
					(thickness 0.15)
				)
			)
		)
		(property "Val" "100n"
			(at 377.8 -73.6 0)
			(layer "F.Fab")
			(hide yes)
			(effects
				(font
					(size 1 1)
					(thickness 0.15)
				)
			)
		)
		(property "Voltage" "50V"
			(at 377.8 -73.6 0)
			(layer "F.Fab")
			(hide yes)
			(effects
				(font
					(size 1 1)
					(thickness 0.15)
				)
			)
		)
		(sheetname "HDMI + Ethernet")
		(sheetfile "hdmi-ethernet.kicad_sch")
		(attr smd)
		(fp_rect
			(start -0.925 -0.47)
			(end 0.925 0.47)
			(stroke
				(width 0.05)
				(type default)
			)
			(fill no)
			(layer "F.CrtYd")
		)
		(fp_line
			(start 0.504 -0.25)
			(end 0.504 0.248)
			(stroke
				(width 0.15)
				(type solid)
			)
			(layer "F.Fab")
		)
		(fp_line
			(start -0.494 -0.25)
			(end 0.504 -0.25)
			(stroke
				(width 0.15)
				(type solid)
			)
			(layer "F.Fab")
		)
		(fp_line
			(start 0.504 0.248)
			(end -0.494 0.248)
			(stroke
				(width 0.15)
				(type solid)
			)
			(layer "F.Fab")
		)
		(fp_line
			(start -0.494 0.248)
			(end -0.494 -0.25)
			(stroke
				(width 0.15)
				(type solid)
			)
			(layer "F.Fab")
		)
		(pad "1" smd roundrect
			(at -0.48 0 90)
			(size 0.59 0.64)
			(layers "F.Cu" "F.Mask" "F.Paste")
			(roundrect_rratio 0.25)
			(net 1 "GND")
			(pintype "passive")
		)
		(pad "2" smd roundrect
			(at 0.48 0 90)
			(size 0.59 0.64)
			(layers "F.Cu" "F.Mask" "F.Paste")
			(roundrect_rratio 0.25)
			(net 721 "/HDMI + Ethernet/ETH_3V3")
			(pintype "passive")
		)
	)
	(footprint "antmicro-footprints:SOT-753"
		(layer "F.Cu")
		(at 163.75 187.1 180)
		(property "Reference" "U35"
			(at 1.1 2.15 180)
			(layer "F.SilkS")
			(effects
				(font
					(size 0.7 0.7)
					(thickness 0.15)
				)
				(justify left bottom)
			)
		)
		(property "Value" "SN74LVC1G125_SOT"
			(at 0 2.9 180)
			(layer "F.Fab")
			(effects
				(font
					(size 0.7 0.7)
					(thickness 0.15)
				)
				(justify left bottom)
			)
		)
		(property "Description" "Buffer, 74LVC1G125, 1.65 V to 5.5 V, SOT-23-5"
			(at 0 0 180)
			(layer "F.Fab")
			(hide yes)
			(effects
				(font
					(size 1.27 1.27)
					(thickness 0.15)
				)
			)
		)
		(property "Author" "Antmicro"
			(at 327.5 374.2 0)
			(layer "F.Fab")
			(hide yes)
			(effects
				(font
					(size 1 1)
					(thickness 0.15)
				)
			)
		)
		(property "License" "Apache-2.0"
			(at 327.5 374.2 0)
			(layer "F.Fab")
			(hide yes)
			(effects
				(font
					(size 1 1)
					(thickness 0.15)
				)
			)
		)
		(property "MPN" "SN74LVC1G125DBVR"
			(at 327.5 374.2 0)
			(layer "F.Fab")
			(hide yes)
			(effects
				(font
					(size 1 1)
					(thickness 0.15)
				)
			)
		)
		(property "Manufacturer" "Texas Instruments"
			(at 327.5 374.2 0)
			(layer "F.Fab")
			(hide yes)
			(effects
				(font
					(size 1 1)
					(thickness 0.15)
				)
			)
		)
		(sheetname "DC-DC Converters")
		(sheetfile "dc-dc.kicad_sch")
		(attr smd)
		(fp_line
			(start 1.648 0.998)
			(end 1.648 0.699)
			(stroke
				(width 0.15)
				(type solid)
			)
			(layer "F.SilkS")
		)
		(fp_line
			(start 1.648 -1)
			(end 1.648 -0.677)
			(stroke
				(width 0.15)
				(type solid)
			)
			(layer "F.SilkS")
		)
		(fp_line
			(start 1.5 0.998)
			(end 1.648 0.998)
			(stroke
				(width 0.15)
				(type solid)
			)
			(layer "F.SilkS")
		)
		(fp_line
			(start 1.5 -1)
			(end 1.648 -1)
			(stroke
				(width 0.15)
				(type solid)
			)
			(layer "F.SilkS")
		)
		(fp_line
			(start -1.5 1)
			(end -1.648 1)
			(stroke
				(width 0.15)
				(type solid)
			)
			(layer "F.SilkS")
		)
		(fp_line
			(start -1.5 -1)
			(end -1.651 -1)
			(stroke
				(width 0.15)
				(type solid)
			)
			(layer "F.SilkS")
		)
		(fp_line
			(start -1.648 1)
			(end -1.648 0.677)
			(stroke
				(width 0.15)
				(type solid)
			)
			(layer "F.SilkS")
		)
		(fp_line
			(start -1.651 -1)
			(end -1.651 -0.701)
			(stroke
				(width 0.15)
				(type solid)
			)
			(layer "F.SilkS")
		)
		(fp_circle
			(center -1.5 1.35)
			(end -1.46 1.4)
			(stroke
				(width 0.15)
				(type solid)
			)
			(fill yes)
			(layer "F.SilkS")
		)
		(fp_rect
			(start -1.7 -1.901)
			(end 1.699 1.898)
			(stroke
				(width 0.05)
				(type solid)
			)
			(fill no)
			(layer "F.CrtYd")
		)
		(fp_line
			(start 1.523 -0.875)
			(end 1.523 0.873)
			(stroke
				(width 0.15)
				(type solid)
			)
			(layer "F.Fab")
		)
		(fp_line
			(start -1.351 0.873)
			(end 1.523 0.873)
			(stroke
				(width 0.15)
				(type solid)
			)
			(layer "F.Fab")
		)
		(fp_line
			(start -1.526 0.623)
			(end -1.351 0.873)
			(stroke
				(width 0.15)
				(type solid)
			)
			(layer "F.Fab")
		)
		(fp_line
			(start -1.526 0.623)
			(end -1.526 -0.875)
			(stroke
				(width 0.15)
				(type solid)
			)
			(layer "F.Fab")
		)
		(fp_line
			(start -1.526 -0.875)
			(end 1.523 -0.875)
			(stroke
				(width 0.15)
				(type solid)
			)
			(layer "F.Fab")
		)
		(pad "1" smd roundrect
			(at -0.951 1.35 180)
			(size 0.6 1.05)
			(layers "F.Cu" "F.Mask" "F.Paste")
			(roundrect_rratio 0.25)
			(net 797 "/DC-DC Converters/PB_CTRL_OE")
			(pinfunction "~{OE}")
			(pintype "input")
		)
		(pad "2" smd roundrect
			(at 0 1.35 180)
			(size 0.6 1.05)
			(layers "F.Cu" "F.Mask" "F.Paste")
			(roundrect_rratio 0.25)
			(net 701 "/DC-DC Converters/PB_CTRL_OUT")
			(pinfunction "A")
			(pintype "input")
		)
		(pad "3" smd roundrect
			(at 0.949 1.35 180)
			(size 0.6 1.05)
			(layers "F.Cu" "F.Mask" "F.Paste")
			(roundrect_rratio 0.25)
			(net 1 "GND")
			(pinfunction "GND")
			(pintype "power_in")
		)
		(pad "4" smd roundrect
			(at 0.949 -1.351 180)
			(size 0.6 1.05)
			(layers "F.Cu" "F.Mask" "F.Paste")
			(roundrect_rratio 0.25)
			(net 961 "/DC-DC Converters/ON{slash}OFF")
			(pinfunction "Y")
			(pintype "output")
		)
		(pad "5" smd roundrect
			(at -0.951 -1.351 180)
			(size 0.6 1.05)
			(layers "F.Cu" "F.Mask" "F.Paste")
			(roundrect_rratio 0.25)
			(net 37 "+3V3_AON")
			(pinfunction "V_{CC}")
			(pintype "power_in")
		)
	)
	(footprint "antmicro-footprints:C_0402_1005Metric"
		(layer "F.Cu")
		(at 218.8 155.1 90)
		(descr "Capacitor SMD 0402")
		(tags "capacitor SMD 0402")
		(property "Reference" "C280"
			(at -1.85 -0.45 270)
			(layer "F.SilkS")
			(effects
				(font
					(size 0.7 0.7)
					(thickness 0.15)
				)
				(justify left bottom)
			)
		)
		(property "Value" "C_10u_0402"
			(at 0 1.4 90)
			(layer "F.Fab")
			(effects
				(font
					(size 0.7 0.7)
					(thickness 0.15)
				)
				(justify left bottom)
			)
		)
		(property "Description" "SMD Multilayer Ceramic Capacitor, 10 µF, 6.3 V, 0402 [1005 Metric], ± 20%, X5R, CC Series"
			(at 0 0 90)
			(layer "F.Fab")
			(hide yes)
			(effects
				(font
					(size 1.27 1.27)
					(thickness 0.15)
				)
			)
		)
		(property "Author" "Antmicro"
			(at 373.9 -63.7 0)
			(layer "F.Fab")
			(hide yes)
			(effects
				(font
					(size 1 1)
					(thickness 0.15)
				)
			)
		)
		(property "Dielectric" ""
			(at 373.9 -63.7 0)
			(layer "F.Fab")
			(hide yes)
			(effects
				(font
					(size 1 1)
					(thickness 0.15)
				)
			)
		)
		(property "License" "Apache-2.0"
			(at 373.9 -63.7 0)
			(layer "F.Fab")
			(hide yes)
			(effects
				(font
					(size 1 1)
					(thickness 0.15)
				)
			)
		)
		(property "MPN" "CC0402MRX5R5BB106"
			(at 373.9 -63.7 0)
			(layer "F.Fab")
			(hide yes)
			(effects
				(font
					(size 1 1)
					(thickness 0.15)
				)
			)
		)
		(property "Manufacturer" "YAGEO"
			(at 373.9 -63.7 0)
			(layer "F.Fab")
			(hide yes)
			(effects
				(font
					(size 1 1)
					(thickness 0.15)
				)
			)
		)
		(property "Val" "10u"
			(at 373.9 -63.7 0)
			(layer "F.Fab")
			(hide yes)
			(effects
				(font
					(size 1 1)
					(thickness 0.15)
				)
			)
		)
		(property "Voltage" ""
			(at 373.9 -63.7 0)
			(layer "F.Fab")
			(hide yes)
			(effects
				(font
					(size 1 1)
					(thickness 0.15)
				)
			)
		)
		(sheetname "HDMI + Ethernet")
		(sheetfile "hdmi-ethernet.kicad_sch")
		(attr smd)
		(fp_rect
			(start -0.925 -0.47)
			(end 0.925 0.47)
			(stroke
				(width 0.05)
				(type default)
			)
			(fill no)
			(layer "F.CrtYd")
		)
		(fp_line
			(start 0.504 -0.25)
			(end 0.504 0.248)
			(stroke
				(width 0.15)
				(type solid)
			)
			(layer "F.Fab")
		)
		(fp_line
			(start -0.494 -0.25)
			(end 0.504 -0.25)
			(stroke
				(width 0.15)
				(type solid)
			)
			(layer "F.Fab")
		)
		(fp_line
			(start 0.504 0.248)
			(end -0.494 0.248)
			(stroke
				(width 0.15)
				(type solid)
			)
			(layer "F.Fab")
		)
		(fp_line
			(start -0.494 0.248)
			(end -0.494 -0.25)
			(stroke
				(width 0.15)
				(type solid)
			)
			(layer "F.Fab")
		)
		(pad "1" smd roundrect
			(at -0.48 0 90)
			(size 0.59 0.64)
			(layers "F.Cu" "F.Mask" "F.Paste")
			(roundrect_rratio 0.25)
			(net 1 "GND")
			(pintype "passive")
		)
		(pad "2" smd roundrect
			(at 0.48 0 90)
			(size 0.59 0.64)
			(layers "F.Cu" "F.Mask" "F.Paste")
			(roundrect_rratio 0.25)
			(net 24 "+3V3")
			(pintype "passive")
		)
	)
)
